(kicad_pcb
	(version 20260206)
	(generator "pcbnew")
	(generator_version "10.0")
	(general
		(thickness 1.6)
		(legacy_teardrops no)
	)
	(paper "A4")
	(title_block
		(title "Wiwynn_Tioga_Pass_MB.brd")
		(comment 1 "Tioga Pass / footprints 1403-1403 of 4770")
	)
	(layers
		(0 "F.Cu" signal "TOP")
		(4 "In1.Cu" signal "L2GND")
		(6 "In2.Cu" signal "L3")
		(8 "In3.Cu" signal "L4GND")
		(10 "In4.Cu" signal "L5")
		(12 "In5.Cu" signal "L6GND")
		(14 "In6.Cu" signal "L7VCC")
		(16 "In7.Cu" signal "L8VCC")
		(18 "In8.Cu" signal "L9GND")
		(20 "In9.Cu" signal "L10")
		(22 "In10.Cu" signal "L11GND")
		(24 "In11.Cu" signal "L12")
		(26 "In12.Cu" signal "L13GND")
		(2 "B.Cu" signal "BOTTOM")
		(9 "F.Adhes" user "F.Adhesive")
		(11 "B.Adhes" user "B.Adhesive")
		(13 "F.Paste" user "Package Geometry/Pastemask Top")
		(15 "B.Paste" user "Package Geometry/Pastemask Bottom")
		(5 "F.SilkS" user "Ref Des/Silkscreen Top")
		(7 "B.SilkS" user "Ref Des/Silkscreen Bottom")
		(1 "F.Mask" user "Board Geometry/Soldermask Top")
		(3 "B.Mask" user "Board Geometry/Soldermask Bottom")
		(17 "Dwgs.User" user "User.Drawings")
		(19 "Cmts.User" user "User.Comments")
		(21 "Eco1.User" user "User.Eco1")
		(23 "Eco2.User" user "User.Eco2")
		(25 "Edge.Cuts" user "Board Geometry/Outline")
		(27 "Margin" user)
		(31 "F.CrtYd" user "Package Geometry/Place Bound Top")
		(29 "B.CrtYd" user "Package Geometry/Place Bound Bottom")
		(35 "F.Fab" user "Ref Des/Assembly Top")
		(33 "B.Fab" user "Ref Des/Assembly Bottom")
	)
	(footprint ""
		(layer "F.Cu")
		(at 437.34101 -47.481998 90)
		(property "Reference" "J8E3"
			(at 6.402832 -4.049014 0)
			(unlocked yes)
			(layer "F.SilkS")
			(effects
				(font
					(size 0.7874 0.5842)
					(thickness 0.1524)
				)
				(justify left)
			)
		)
		(property "Value" ""
			(at 0 0 90)
			(layer "F.Fab")
			(effects
				(font
					(size 1.27 1.27)
				)
			)
		)
		(duplicate_pad_numbers_are_jumpers no)
		(fp_line
			(start 5.25907 -3.374898)
			(end 5.25907 -0.90805)
			(stroke
				(width 0.151892)
				(type default)
			)
			(layer "F.SilkS")
		)
		(fp_line
			(start 3.116072 -3.374898)
			(end 5.25907 -3.374898)
			(stroke
				(width 0.151892)
				(type default)
			)
			(layer "F.SilkS")
		)
		(fp_line
			(start -0.878078 -3.374898)
			(end 1.32588 -3.374898)
			(stroke
				(width 0.151892)
				(type default)
			)
			(layer "F.SilkS")
		)
		(fp_line
			(start -0.878078 -0.932942)
			(end -0.878078 -3.374898)
			(stroke
				(width 0.151892)
				(type default)
			)
			(layer "F.SilkS")
		)
		(fp_line
			(start 5.272024 32.109918)
			(end 5.272024 34.574988)
			(stroke
				(width 0.151892)
				(type default)
			)
			(layer "F.SilkS")
		)
		(fp_line
			(start 5.272024 34.574988)
			(end 3.228086 34.574988)
			(stroke
				(width 0.151892)
				(type default)
			)
			(layer "F.SilkS")
		)
		(fp_line
			(start 1.178052 34.574988)
			(end -0.877824 34.574988)
			(stroke
				(width 0.151892)
				(type default)
			)
			(layer "F.SilkS")
		)
		(fp_line
			(start -0.877824 34.574988)
			(end -0.877824 32.175958)
			(stroke
				(width 0.151892)
				(type default)
			)
			(layer "F.SilkS")
		)
		(fp_poly
			(pts
				(xy -2.36347 0.692404) (xy -2.36347 -0.323596) (xy -1.09347 0.184404)
			)
			(stroke
				(width 0)
				(type default)
			)
			(fill yes)
			(layer "F.SilkS")
		)
		(fp_rect
			(start -0.878078 34.574988)
			(end 5.272024 -3.374898)
			(stroke
				(width 0)
				(type default)
			)
			(fill no)
			(layer "F.CrtYd")
		)
		(fp_line
			(start 5.272024 -3.374898)
			(end 5.272024 34.574988)
			(stroke
				(width 0.1)
				(type default)
			)
			(layer "F.Fab")
		)
		(fp_line
			(start -0.878078 -3.374898)
			(end 5.272024 -3.374898)
			(stroke
				(width 0.1)
				(type default)
			)
			(layer "F.Fab")
		)
		(fp_line
			(start 5.272024 34.574988)
			(end -0.878078 34.574988)
			(stroke
				(width 0.1)
				(type default)
			)
			(layer "F.Fab")
		)
		(fp_line
			(start -0.878078 34.574988)
			(end -0.878078 -3.374898)
			(stroke
				(width 0.1)
				(type default)
			)
			(layer "F.Fab")
		)
		(fp_text user "2"
			(at 6.2357 -0.108712 0)
			(unlocked yes)
			(layer "F.SilkS")
			(effects
				(font
					(size 0.7874 0.5842)
					(thickness 0.1524)
				)
				(justify left)
			)
		)
		(fp_text user " 79"
			(at -4.289552 31.10357 90)
			(unlocked yes)
			(layer "F.SilkS")
			(effects
				(font
					(size 0.7874 0.5842)
					(thickness 0.1524)
				)
				(justify left)
			)
		)
		(fp_text user "80"
			(at 6.085332 32.052006 0)
			(unlocked yes)
			(layer "F.SilkS")
			(effects
				(font
					(size 0.7874 0.5842)
					(thickness 0.1524)
				)
				(justify left)
			)
		)
		(fp_text user "2"
			(at 6.496812 -1.275715 90)
			(unlocked yes)
			(layer "F.Fab")
			(effects
				(font
					(size 0.8001 0.598932)
					(thickness 0.000001)
				)
				(justify left)
			)
		)
		(fp_text user "80"
			(at 6.04901 31.270067 90)
			(unlocked yes)
			(layer "F.Fab")
			(effects
				(font
					(size 0.8001 0.598932)
					(thickness 0.000001)
				)
				(justify left)
			)
		)
		(fp_text user " 79"
			(at -2.219198 32.530161 90)
			(unlocked yes)
			(layer "F.Fab")
			(effects
				(font
					(size 0.8001 0.598932)
					(thickness 0.000001)
				)
				(justify left)
			)
		)
		(pad "" np_thru_hole circle
			(at 2.1971 -2.489962 90)
			(size 0.254 0.254)
			(drill 1.3716)
			(layers "*.Cu" "*.Mask")
			(clearance 0.8763)
			(thermal_gap 0.8763)
		)
		(pad "" np_thru_hole circle
			(at 2.1971 33.702244 90)
			(size 0.254 0.254)
			(drill 1.016)
			(layers "*.Cu" "*.Mask")
			(clearance 0.6985)
			(thermal_gap 0.6985)
		)
		(pad "1" smd rect
			(at 0 0 90)
			(size 2.0066 0.508)
			(layers "F.Cu" "F.Mask" "F.Paste")
			(net "FM_MEZZB_PRSNT1_N")
		)
		(pad "2" smd rect
			(at 4.393946 0 90)
			(size 2.0066 0.508)
			(layers "F.Cu" "F.Mask" "F.Paste")
			(net "P12V_STBY")
		)
		(pad "3" smd rect
			(at 0 0.8001 90)
			(size 2.0066 0.508)
			(layers "F.Cu" "F.Mask" "F.Paste")
			(net "GND")
		)
		(pad "4" smd rect
			(at 4.393946 0.8001 90)
			(size 2.0066 0.508)
			(layers "F.Cu" "F.Mask" "F.Paste")
			(net "P12V_STBY")
		)
		(pad "5" smd rect
			(at 0 1.599946 90)
			(size 2.0066 0.508)
			(layers "F.Cu" "F.Mask" "F.Paste")
			(net "P3E_CPU0_PE3_OCP_RXP<7>")
		)
		(pad "6" smd rect
			(at 4.393946 1.599946 90)
			(size 2.0066 0.508)
			(layers "F.Cu" "F.Mask" "F.Paste")
			(net "TP_RSVD_B1")
		)
		(pad "7" smd rect
			(at 0 2.400046 90)
			(size 2.0066 0.508)
			(layers "F.Cu" "F.Mask" "F.Paste")
			(net "P3E_CPU0_PE3_OCP_RXN<7>")
		)
		(pad "8" smd rect
			(at 4.393946 2.400046 90)
			(size 2.0066 0.508)
			(layers "F.Cu" "F.Mask" "F.Paste")
			(net "GND")
		)
		(pad "9" smd rect
			(at 0 3.199892 90)
			(size 2.0066 0.508)
			(layers "F.Cu" "F.Mask" "F.Paste")
			(net "GND")
		)
		(pad "10" smd rect
			(at 4.393946 3.199892 90)
			(size 2.0066 0.508)
			(layers "F.Cu" "F.Mask" "F.Paste")
			(net "P3E_OCP_CPU0_PE3_C_TXP<7>")
		)
		(pad "11" smd rect
			(at 0 3.999992 90)
			(size 2.0066 0.508)
			(layers "F.Cu" "F.Mask" "F.Paste")
			(net "GND")
		)
		(pad "12" smd rect
			(at 4.393946 3.999992 90)
			(size 2.0066 0.508)
			(layers "F.Cu" "F.Mask" "F.Paste")
			(net "P3E_OCP_CPU0_PE3_C_TXN<7>")
		)
		(pad "13" smd rect
			(at 0 4.800092 90)
			(size 2.0066 0.508)
			(layers "F.Cu" "F.Mask" "F.Paste")
			(net "P3E_CPU0_PE3_OCP_RXN<6>")
		)
		(pad "14" smd rect
			(at 4.393946 4.800092 90)
			(size 2.0066 0.508)
			(layers "F.Cu" "F.Mask" "F.Paste")
			(net "GND")
		)
		(pad "15" smd rect
			(at 0 5.599938 90)
			(size 2.0066 0.508)
			(layers "F.Cu" "F.Mask" "F.Paste")
			(net "P3E_CPU0_PE3_OCP_RXP<6>")
		)
		(pad "16" smd rect
			(at 4.393946 5.599938 90)
			(size 2.0066 0.508)
			(layers "F.Cu" "F.Mask" "F.Paste")
			(net "GND")
		)
		(pad "17" smd rect
			(at 0 6.400038 90)
			(size 2.0066 0.508)
			(layers "F.Cu" "F.Mask" "F.Paste")
			(net "GND")
		)
		(pad "18" smd rect
			(at 4.393946 6.400038 90)
			(size 2.0066 0.508)
			(layers "F.Cu" "F.Mask" "F.Paste")
			(net "P3E_OCP_CPU0_PE3_C_TXP<6>")
		)
		(pad "19" smd rect
			(at 0 7.199884 90)
			(size 2.0066 0.508)
			(layers "F.Cu" "F.Mask" "F.Paste")
			(net "GND")
		)
		(pad "20" smd rect
			(at 4.393946 7.199884 90)
			(size 2.0066 0.508)
			(layers "F.Cu" "F.Mask" "F.Paste")
			(net "P3E_OCP_CPU0_PE3_C_TXN<6>")
		)
		(pad "21" smd rect
			(at 0 7.999984 90)
			(size 2.0066 0.508)
			(layers "F.Cu" "F.Mask" "F.Paste")
			(net "P3E_CPU0_PE3_OCP_RXN<5>")
		)
		(pad "22" smd rect
			(at 4.393946 7.999984 90)
			(size 2.0066 0.508)
			(layers "F.Cu" "F.Mask" "F.Paste")
			(net "GND")
		)
		(pad "23" smd rect
			(at 0 8.800084 90)
			(size 2.0066 0.508)
			(layers "F.Cu" "F.Mask" "F.Paste")
			(net "P3E_CPU0_PE3_OCP_RXP<5>")
		)
		(pad "24" smd rect
			(at 4.393946 8.800084 90)
			(size 2.0066 0.508)
			(layers "F.Cu" "F.Mask" "F.Paste")
			(net "GND")
		)
		(pad "25" smd rect
			(at 0 9.59993 90)
			(size 2.0066 0.508)
			(layers "F.Cu" "F.Mask" "F.Paste")
			(net "GND")
		)
		(pad "26" smd rect
			(at 4.393946 9.59993 90)
			(size 2.0066 0.508)
			(layers "F.Cu" "F.Mask" "F.Paste")
			(net "P3E_OCP_CPU0_PE3_C_TXP<5>")
		)
		(pad "27" smd rect
			(at 0 10.40003 90)
			(size 2.0066 0.508)
			(layers "F.Cu" "F.Mask" "F.Paste")
			(net "GND")
		)
		(pad "28" smd rect
			(at 4.393946 10.40003 90)
			(size 2.0066 0.508)
			(layers "F.Cu" "F.Mask" "F.Paste")
			(net "P3E_OCP_CPU0_PE3_C_TXN<5>")
		)
		(pad "29" smd rect
			(at 0 11.199876 90)
			(size 2.0066 0.508)
			(layers "F.Cu" "F.Mask" "F.Paste")
			(net "P3E_CPU0_PE3_OCP_RXN<4>")
		)
		(pad "30" smd rect
			(at 4.393946 11.199876 90)
			(size 2.0066 0.508)
			(layers "F.Cu" "F.Mask" "F.Paste")
			(net "GND")
		)
		(pad "31" smd rect
			(at 0 11.999976 90)
			(size 2.0066 0.508)
			(layers "F.Cu" "F.Mask" "F.Paste")
			(net "P3E_CPU0_PE3_OCP_RXP<4>")
		)
		(pad "32" smd rect
			(at 4.393946 11.999976 90)
			(size 2.0066 0.508)
			(layers "F.Cu" "F.Mask" "F.Paste")
			(net "GND")
		)
		(pad "33" smd rect
			(at 0 12.800076 90)
			(size 2.0066 0.508)
			(layers "F.Cu" "F.Mask" "F.Paste")
			(net "GND")
		)
		(pad "34" smd rect
			(at 4.393946 12.800076 90)
			(size 2.0066 0.508)
			(layers "F.Cu" "F.Mask" "F.Paste")
			(net "P3E_OCP_CPU0_PE3_C_TXP<4>")
		)
		(pad "35" smd rect
			(at 0 13.599922 90)
			(size 2.0066 0.508)
			(layers "F.Cu" "F.Mask" "F.Paste")
			(net "GND")
		)
		(pad "36" smd rect
			(at 4.393946 13.599922 90)
			(size 2.0066 0.508)
			(layers "F.Cu" "F.Mask" "F.Paste")
			(net "P3E_OCP_CPU0_PE3_C_TXN<4>")
		)
		(pad "37" smd rect
			(at 0 14.400022 90)
			(size 2.0066 0.508)
			(layers "F.Cu" "F.Mask" "F.Paste")
			(net "P3E_CPU0_PE3_OCP_RXP<3>")
		)
		(pad "38" smd rect
			(at 4.393946 14.400022 90)
			(size 2.0066 0.508)
			(layers "F.Cu" "F.Mask" "F.Paste")
			(net "GND")
		)
		(pad "39" smd rect
			(at 0 15.200122 90)
			(size 2.0066 0.508)
			(layers "F.Cu" "F.Mask" "F.Paste")
			(net "P3E_CPU0_PE3_OCP_RXN<3>")
		)
		(pad "40" smd rect
			(at 4.393946 15.200122 90)
			(size 2.0066 0.508)
			(layers "F.Cu" "F.Mask" "F.Paste")
			(net "GND")
		)
		(pad "41" smd rect
			(at 0 15.999968 90)
			(size 2.0066 0.508)
			(layers "F.Cu" "F.Mask" "F.Paste")
			(net "GND")
		)
		(pad "42" smd rect
			(at 4.393946 15.999968 90)
			(size 2.0066 0.508)
			(layers "F.Cu" "F.Mask" "F.Paste")
			(net "P3E_OCP_CPU0_PE3_C_TXP<3>")
		)
		(pad "43" smd rect
			(at 0 16.800068 90)
			(size 2.0066 0.508)
			(layers "F.Cu" "F.Mask" "F.Paste")
			(net "GND")
		)
		(pad "44" smd rect
			(at 4.393946 16.800068 90)
			(size 2.0066 0.508)
			(layers "F.Cu" "F.Mask" "F.Paste")
			(net "P3E_OCP_CPU0_PE3_C_TXN<3>")
		)
		(pad "45" smd rect
			(at 0 17.599914 90)
			(size 2.0066 0.508)
			(layers "F.Cu" "F.Mask" "F.Paste")
			(net "P3E_CPU0_PE3_OCP_RXP<2>")
		)
		(pad "46" smd rect
			(at 4.393946 17.599914 90)
			(size 2.0066 0.508)
			(layers "F.Cu" "F.Mask" "F.Paste")
			(net "GND")
		)
		(pad "47" smd rect
			(at 0 18.400014 90)
			(size 2.0066 0.508)
			(layers "F.Cu" "F.Mask" "F.Paste")
			(net "P3E_CPU0_PE3_OCP_RXN<2>")
		)
		(pad "48" smd rect
			(at 4.393946 18.400014 90)
			(size 2.0066 0.508)
			(layers "F.Cu" "F.Mask" "F.Paste")
			(net "GND")
		)
		(pad "49" smd rect
			(at 0 19.200114 90)
			(size 2.0066 0.508)
			(layers "F.Cu" "F.Mask" "F.Paste")
			(net "GND")
		)
		(pad "50" smd rect
			(at 4.393946 19.200114 90)
			(size 2.0066 0.508)
			(layers "F.Cu" "F.Mask" "F.Paste")
			(net "P3E_OCP_CPU0_PE3_C_TXP<2>")
		)
		(pad "51" smd rect
			(at 0 19.99996 90)
			(size 2.0066 0.508)
			(layers "F.Cu" "F.Mask" "F.Paste")
			(net "GND")
		)
		(pad "52" smd rect
			(at 4.393946 19.99996 90)
			(size 2.0066 0.508)
			(layers "F.Cu" "F.Mask" "F.Paste")
			(net "P3E_OCP_CPU0_PE3_C_TXN<2>")
		)
		(pad "53" smd rect
			(at 0 20.80006 90)
			(size 2.0066 0.508)
			(layers "F.Cu" "F.Mask" "F.Paste")
			(net "P3E_CPU0_PE3_OCP_RXP<1>")
		)
		(pad "54" smd rect
			(at 4.393946 20.80006 90)
			(size 2.0066 0.508)
			(layers "F.Cu" "F.Mask" "F.Paste")
			(net "GND")
		)
		(pad "55" smd rect
			(at 0 21.599906 90)
			(size 2.0066 0.508)
			(layers "F.Cu" "F.Mask" "F.Paste")
			(net "P3E_CPU0_PE3_OCP_RXN<1>")
		)
		(pad "56" smd rect
			(at 4.393946 21.599906 90)
			(size 2.0066 0.508)
			(layers "F.Cu" "F.Mask" "F.Paste")
			(net "GND")
		)
		(pad "57" smd rect
			(at 0 22.400006 90)
			(size 2.0066 0.508)
			(layers "F.Cu" "F.Mask" "F.Paste")
			(net "GND")
		)
		(pad "58" smd rect
			(at 4.393946 22.400006 90)
			(size 2.0066 0.508)
			(layers "F.Cu" "F.Mask" "F.Paste")
			(net "P3E_OCP_CPU0_PE3_C_TXP<1>")
		)
		(pad "59" smd rect
			(at 0 23.200106 90)
			(size 2.0066 0.508)
			(layers "F.Cu" "F.Mask" "F.Paste")
			(net "GND")
		)
		(pad "60" smd rect
			(at 4.393946 23.200106 90)
			(size 2.0066 0.508)
			(layers "F.Cu" "F.Mask" "F.Paste")
			(net "P3E_OCP_CPU0_PE3_C_TXN<1>")
		)
		(pad "61" smd rect
			(at 0 23.999952 90)
			(size 2.0066 0.508)
			(layers "F.Cu" "F.Mask" "F.Paste")
			(net "P3E_CPU0_PE3_OCP_RXP<0>")
		)
		(pad "62" smd rect
			(at 4.393946 23.999952 90)
			(size 2.0066 0.508)
			(layers "F.Cu" "F.Mask" "F.Paste")
			(net "GND")
		)
		(pad "63" smd rect
			(at 0 24.800052 90)
			(size 2.0066 0.508)
			(layers "F.Cu" "F.Mask" "F.Paste")
			(net "P3E_CPU0_PE3_OCP_RXN<0>")
		)
		(pad "64" smd rect
			(at 4.393946 24.800052 90)
			(size 2.0066 0.508)
			(layers "F.Cu" "F.Mask" "F.Paste")
			(net "GND")
		)
		(pad "65" smd rect
			(at 0 25.599898 90)
			(size 2.0066 0.508)
			(layers "F.Cu" "F.Mask" "F.Paste")
			(net "GND")
		)
		(pad "66" smd rect
			(at 4.393946 25.599898 90)
			(size 2.0066 0.508)
			(layers "F.Cu" "F.Mask" "F.Paste")
			(net "P3E_OCP_CPU0_PE3_C_TXP<0>")
		)
		(pad "67" smd rect
			(at 0 26.399998 90)
			(size 2.0066 0.508)
			(layers "F.Cu" "F.Mask" "F.Paste")
			(net "GND")
		)
		(pad "68" smd rect
			(at 4.393946 26.399998 90)
			(size 2.0066 0.508)
			(layers "F.Cu" "F.Mask" "F.Paste")
			(net "P3E_OCP_CPU0_PE3_C_TXN<0>")
		)
		(pad "69" smd rect
			(at 0 27.200098 90)
			(size 2.0066 0.508)
			(layers "F.Cu" "F.Mask" "F.Paste")
			(net "CLK_100M_MEZZ3_DP")
		)
		(pad "70" smd rect
			(at 4.393946 27.200098 90)
			(size 2.0066 0.508)
			(layers "F.Cu" "F.Mask" "F.Paste")
			(net "GND")
		)
		(pad "71" smd rect
			(at 0 27.999944 90)
			(size 2.0066 0.508)
			(layers "F.Cu" "F.Mask" "F.Paste")
			(net "CLK_100M_MEZZ3_DN")
		)
		(pad "72" smd rect
			(at 4.393946 27.999944 90)
			(size 2.0066 0.508)
			(layers "F.Cu" "F.Mask" "F.Paste")
			(net "GND")
		)
		(pad "73" smd rect
			(at 0 28.800044 90)
			(size 2.0066 0.508)
			(layers "F.Cu" "F.Mask" "F.Paste")
			(net "GND")
		)
		(pad "74" smd rect
			(at 4.393946 28.800044 90)
			(size 2.0066 0.508)
			(layers "F.Cu" "F.Mask" "F.Paste")
			(net "CLK_100M_MEZZ4_DP")
		)
		(pad "75" smd rect
			(at 0 29.59989 90)
			(size 2.0066 0.508)
			(layers "F.Cu" "F.Mask" "F.Paste")
			(net "RST_PCIE_CPU_DEV1_R_N")
		)
		(pad "76" smd rect
			(at 4.393946 29.59989 90)
			(size 2.0066 0.508)
			(layers "F.Cu" "F.Mask" "F.Paste")
			(net "CLK_100M_MEZZ4_DN")
		)
		(pad "77" smd rect
			(at 0 30.39999 90)
			(size 2.0066 0.508)
			(layers "F.Cu" "F.Mask" "F.Paste")
			(net "RST_PCIE_CPU_DEV2_R_N")
		)
		(pad "78" smd rect
			(at 4.393946 30.39999 90)
			(size 2.0066 0.508)
			(layers "F.Cu" "F.Mask" "F.Paste")
			(net "GND")
		)
		(pad "79" smd rect
			(at 0 31.20009 90)
			(size 2.0066 0.508)
			(layers "F.Cu" "F.Mask" "F.Paste")
			(net "RST_PCIE_CPU_DEV3_R_N")
		)
		(pad "80" smd rect
			(at 4.393946 31.20009 90)
			(size 2.0066 0.508)
			(layers "F.Cu" "F.Mask" "F.Paste")
			(net "FM_OCP_MEZZB_PRES_N")
		)
		(zone
			(layers "F.Cu" "B.Cu" "In1.Cu" "In2.Cu" "In3.Cu" "In4.Cu" "In5.Cu" "In6.Cu"
				"In7.Cu" "In8.Cu" "In9.Cu" "In10.Cu" "In11.Cu" "In12.Cu"
			)
			(hatch none 0.5)
			(connect_pads
				(clearance 0)
			)
			(min_thickness 0.25)
			(keepout
				(tracks not_allowed)
				(vias allowed)
				(pads allowed)
				(copperpour not_allowed)
				(footprints allowed)
			)
			(placement
				(enabled no)
				(sheetname "")
			)
			(fill
				(thermal_gap 0.5)
				(thermal_bridge_width 0.5)
				(island_removal_mode 0)
			)
			(polygon
				(pts
					(arc
						(start 471.868754 -49.679098)
						(mid 470.217754 -49.679098)
						(end 471.868754 -49.679098)
					)
				)
			)
		)
		(zone
			(layers "F.Cu" "B.Cu" "In1.Cu" "In2.Cu" "In3.Cu" "In4.Cu" "In5.Cu" "In6.Cu"
				"In7.Cu" "In8.Cu" "In9.Cu" "In10.Cu" "In11.Cu" "In12.Cu"
			)
			(hatch none 0.5)
			(connect_pads
				(clearance 0)
			)
			(min_thickness 0.25)
			(keepout
				(tracks not_allowed)
				(vias allowed)
				(pads allowed)
				(copperpour not_allowed)
				(footprints allowed)
			)
			(placement
				(enabled no)
				(sheetname "")
			)
			(fill
				(thermal_gap 0.5)
				(thermal_bridge_width 0.5)
				(island_removal_mode 0)
			)
			(polygon
				(pts
					(arc
						(start 435.854348 -49.679098)
						(mid 433.847748 -49.679098)
						(end 435.854348 -49.679098)
					)
				)
			)
		)
	)
)
